# S9S_MB_2U (Grand Teton) — schematic netlist excerpt (pin names and nets, part order shuffled) for the footprints in the layout excerpt that follows; sources: Cadence DE-HDL packaged netlist, KiCad conversion of 03242023_DA0F0TMBIJ0_F0T_Motherboard_J_brd_V01_OCP.brd

C103  Q_CAP  27PF 50V 5% EMPTY  pkg 0402  page 179 : A = XTAL_PCH_25M_IN_R ; B = GND
PR3823  Q_RES  845 1% EMPTY  pkg 0402LF  page 162 : A = P12V_OCP_SENSE_2 ; B = GND
C888  Q_CAP_DIFFBUS  DIFF BUS_0.22UF 6.3V 20% X6S  pkg C0201  page 174 : \1\ = P5E_CPU0_PE3_TX_C_DN<6> ; \2\ = P5E_CPU0_PE3_TX_DN<6>

(kicad_pcb
	(version 20260206)
	(generator "pcbnew")
	(generator_version "10.0")
	(general
		(thickness 1.6)
		(legacy_teardrops no)
	)
	(paper "A4")
	(title_block
		(title "03242023_DA0F0TMBIJ0_F0T_Motherboard_J_brd_V01_OCP.brd")
		(comment 1 "Grand Teton / footprints 441-443 of 6105")
	)
	(layers
		(0 "F.Cu" signal "TOP")
		(4 "In1.Cu" signal "GND")
		(6 "In2.Cu" signal "IN1")
		(8 "In3.Cu" signal "GND1")
		(10 "In4.Cu" signal "IN2")
		(12 "In5.Cu" signal "GND2")
		(14 "In6.Cu" signal "IN3")
		(16 "In7.Cu" signal "GND3")
		(18 "In8.Cu" signal "VCC")
		(20 "In9.Cu" signal "VCC1")
		(22 "In10.Cu" signal "GND4")
		(24 "In11.Cu" signal "IN4")
		(26 "In12.Cu" signal "GND5")
		(28 "In13.Cu" signal "IN5")
		(30 "In14.Cu" signal "GND6")
		(32 "In15.Cu" signal "IN6")
		(34 "In16.Cu" signal "GND7")
		(2 "B.Cu" signal "BOTTOM")
		(9 "F.Adhes" user "F.Adhesive")
		(11 "B.Adhes" user "B.Adhesive")
		(13 "F.Paste" user "Package Geometry/Pastemask Top")
		(15 "B.Paste" user "Package Geometry/Pastemask Bottom")
		(5 "F.SilkS" user "Ref Des/Silkscreen Top")
		(7 "B.SilkS" user "Ref Des/Silkscreen Bottom")
		(1 "F.Mask" user "Board Geometry/Soldermask Top")
		(3 "B.Mask" user "Board Geometry/Soldermask Bottom")
		(17 "Dwgs.User" user "User.Drawings")
		(19 "Cmts.User" user "User.Comments")
		(21 "Eco1.User" user "User.Eco1")
		(23 "Eco2.User" user "User.Eco2")
		(25 "Edge.Cuts" user "Board Geometry/Outline")
		(27 "Margin" user)
		(31 "F.CrtYd" user "Package Geometry/Place Bound Top")
		(29 "B.CrtYd" user "Package Geometry/Place Bound Bottom")
		(35 "F.Fab" user "Ref Des/Assembly Top")
		(33 "B.Fab" user "Ref Des/Assembly Bottom")
	)
	(footprint ""
		(layer "F.Cu")
		(at 334.7212 -66.462148 180)
		(property "Reference" "C103"
			(at 0 0 180)
			(layer "F.SilkS")
			(hide yes)
			(effects
				(font
					(size 1.27 1.27)
				)
			)
		)
		(property "Value" ""
			(at 0 0 180)
			(layer "F.Fab")
			(effects
				(font
					(size 1.27 1.27)
				)
			)
		)
		(duplicate_pad_numbers_are_jumpers no)
		(fp_line
			(start 0.7874 0.4064)
			(end -0.7874 0.4064)
			(stroke
				(width 0.1524)
				(type default)
			)
			(layer "F.SilkS")
		)
		(fp_line
			(start 0.7874 -0.4064)
			(end 0.7874 0.4064)
			(stroke
				(width 0.1524)
				(type default)
			)
			(layer "F.SilkS")
		)
		(fp_line
			(start -0.7874 0.4064)
			(end -0.7874 -0.4064)
			(stroke
				(width 0.1524)
				(type default)
			)
			(layer "F.SilkS")
		)
		(fp_line
			(start -0.7874 -0.4064)
			(end 0.7874 -0.4064)
			(stroke
				(width 0.1524)
				(type default)
			)
			(layer "F.SilkS")
		)
		(fp_line
			(start 0.67945 0.3048)
			(end 0.120396 0.3048)
			(stroke
				(width 0.1)
				(type default)
			)
			(layer "F.Fab")
		)
		(fp_line
			(start 0.67945 -0.3048)
			(end 0.67945 0.3048)
			(stroke
				(width 0.1)
				(type default)
			)
			(layer "F.Fab")
		)
		(fp_line
			(start 0.12065 -0.2794)
			(end 0.12065 -0.3048)
			(stroke
				(width 0.1)
				(type default)
			)
			(layer "F.Fab")
		)
		(fp_line
			(start 0.12065 -0.3048)
			(end 0.67945 -0.3048)
			(stroke
				(width 0.1)
				(type default)
			)
			(layer "F.Fab")
		)
		(fp_line
			(start 0.120396 0.3048)
			(end 0.120396 0.2794)
			(stroke
				(width 0.1)
				(type default)
			)
			(layer "F.Fab")
		)
		(fp_line
			(start 0.120396 0.2794)
			(end -0.12065 0.2794)
			(stroke
				(width 0.1)
				(type default)
			)
			(layer "F.Fab")
		)
		(fp_line
			(start -0.12065 0.3048)
			(end -0.67945 0.3048)
			(stroke
				(width 0.1)
				(type default)
			)
			(layer "F.Fab")
		)
		(fp_line
			(start -0.12065 0.2794)
			(end -0.12065 0.3048)
			(stroke
				(width 0.1)
				(type default)
			)
			(layer "F.Fab")
		)
		(fp_line
			(start -0.12065 -0.2794)
			(end 0.12065 -0.2794)
			(stroke
				(width 0.1)
				(type default)
			)
			(layer "F.Fab")
		)
		(fp_line
			(start -0.12065 -0.305054)
			(end -0.12065 -0.2794)
			(stroke
				(width 0.1)
				(type default)
			)
			(layer "F.Fab")
		)
		(fp_line
			(start -0.67945 0.3048)
			(end -0.67945 -0.305054)
			(stroke
				(width 0.1)
				(type default)
			)
			(layer "F.Fab")
		)
		(fp_line
			(start -0.67945 -0.305054)
			(end -0.12065 -0.305054)
			(stroke
				(width 0.1)
				(type default)
			)
			(layer "F.Fab")
		)
		(pad "1" smd circle
			(at -0.40005 0 180)
			(size 0 0)
			(layers "F.Cu" "F.Mask" "F.Paste")
			(net "XTAL_PCH_25M_IN_R")
		)
		(pad "2" smd circle
			(at 0.40005 0 180)
			(size 0 0)
			(layers "F.Cu" "F.Mask" "F.Paste")
			(net "GND")
		)
	)
	(footprint ""
		(layer "F.Cu")
		(at 75.546458 -21.839682 180)
		(property "Reference" "PR3823"
			(at 0 0 180)
			(layer "F.SilkS")
			(hide yes)
			(effects
				(font
					(size 1.27 1.27)
				)
			)
		)
		(property "Value" ""
			(at 0 0 180)
			(layer "F.Fab")
			(effects
				(font
					(size 1.27 1.27)
				)
			)
		)
		(duplicate_pad_numbers_are_jumpers no)
		(fp_line
			(start 0.7874 0.4064)
			(end -0.7874 0.4064)
			(stroke
				(width 0.1524)
				(type default)
			)
			(layer "F.SilkS")
		)
		(fp_line
			(start 0.7874 -0.4064)
			(end 0.7874 0.4064)
			(stroke
				(width 0.1524)
				(type default)
			)
			(layer "F.SilkS")
		)
		(fp_line
			(start -0.7874 0.4064)
			(end -0.7874 -0.4064)
			(stroke
				(width 0.1524)
				(type default)
			)
			(layer "F.SilkS")
		)
		(fp_line
			(start -0.7874 -0.4064)
			(end 0.7874 -0.4064)
			(stroke
				(width 0.1524)
				(type default)
			)
			(layer "F.SilkS")
		)
		(fp_line
			(start 0.67945 0.3048)
			(end 0.120396 0.3048)
			(stroke
				(width 0.1)
				(type default)
			)
			(layer "F.Fab")
		)
		(fp_line
			(start 0.67945 -0.3048)
			(end 0.67945 0.3048)
			(stroke
				(width 0.1)
				(type default)
			)
			(layer "F.Fab")
		)
		(fp_line
			(start 0.12065 -0.2794)
			(end 0.12065 -0.3048)
			(stroke
				(width 0.1)
				(type default)
			)
			(layer "F.Fab")
		)
		(fp_line
			(start 0.12065 -0.3048)
			(end 0.67945 -0.3048)
			(stroke
				(width 0.1)
				(type default)
			)
			(layer "F.Fab")
		)
		(fp_line
			(start 0.120396 0.3048)
			(end 0.120396 0.2794)
			(stroke
				(width 0.1)
				(type default)
			)
			(layer "F.Fab")
		)
		(fp_line
			(start 0.120396 0.2794)
			(end -0.12065 0.2794)
			(stroke
				(width 0.1)
				(type default)
			)
			(layer "F.Fab")
		)
		(fp_line
			(start -0.12065 0.3048)
			(end -0.67945 0.3048)
			(stroke
				(width 0.1)
				(type default)
			)
			(layer "F.Fab")
		)
		(fp_line
			(start -0.12065 0.2794)
			(end -0.12065 0.3048)
			(stroke
				(width 0.1)
				(type default)
			)
			(layer "F.Fab")
		)
		(fp_line
			(start -0.12065 -0.2794)
			(end 0.12065 -0.2794)
			(stroke
				(width 0.1)
				(type default)
			)
			(layer "F.Fab")
		)
		(fp_line
			(start -0.12065 -0.305054)
			(end -0.12065 -0.2794)
			(stroke
				(width 0.1)
				(type default)
			)
			(layer "F.Fab")
		)
		(fp_line
			(start -0.67945 0.3048)
			(end -0.67945 -0.305054)
			(stroke
				(width 0.1)
				(type default)
			)
			(layer "F.Fab")
		)
		(fp_line
			(start -0.67945 -0.305054)
			(end -0.12065 -0.305054)
			(stroke
				(width 0.1)
				(type default)
			)
			(layer "F.Fab")
		)
		(pad "1" smd circle
			(at -0.40005 0 180)
			(size 0 0)
			(layers "F.Cu" "F.Mask" "F.Paste")
			(net "P12V_OCP_SENSE_2")
		)
		(pad "2" smd circle
			(at 0.40005 0 180)
			(size 0 0)
			(layers "F.Cu" "F.Mask" "F.Paste")
			(net "GND")
		)
	)
	(footprint ""
		(layer "F.Cu")
		(at 400.31289 -408.517344 -90)
		(property "Reference" "C888"
			(at 0 0 270)
			(layer "F.SilkS")
			(hide yes)
			(effects
				(font
					(size 1.27 1.27)
				)
			)
		)
		(property "Value" ""
			(at 0 0 270)
			(layer "F.Fab")
			(effects
				(font
					(size 1.27 1.27)
				)
			)
		)
		(duplicate_pad_numbers_are_jumpers no)
		(fp_line
			(start -0.299974 0.150114)
			(end -0.299974 -0.150114)
			(stroke
				(width 0.1)
				(type default)
			)
			(layer "F.Fab")
		)
		(fp_line
			(start 0.299974 0.150114)
			(end -0.299974 0.150114)
			(stroke
				(width 0.1)
				(type default)
			)
			(layer "F.Fab")
		)
		(fp_line
			(start -0.299974 -0.150114)
			(end 0.299974 -0.150114)
			(stroke
				(width 0.1)
				(type default)
			)
			(layer "F.Fab")
		)
		(fp_line
			(start 0.299974 -0.150114)
			(end 0.299974 0.150114)
			(stroke
				(width 0.1)
				(type default)
			)
			(layer "F.Fab")
		)
		(pad "1" smd rect
			(at -0.2667 0 270)
			(size 0.3048 0.381)
			(layers "F.Cu" "F.Mask" "F.Paste")
			(net "P5E_CPU0_PE3_TX_C_DN<6>")
		)
		(pad "2" smd rect
			(at 0.2667 0 270)
			(size 0.3048 0.381)
			(layers "F.Cu" "F.Mask" "F.Paste")
			(net "P5E_CPU0_PE3_TX_DN<6>")
		)
	)
)
